FILE_TYPE = CONNECTIVITY;
{Allegro Design Entry HDL 17.4-2019 S026 (4007227) 1/17/2022}
"PAGE_NUMBER" = 159;
0"NC";
END.
